FILE_TYPE = MULTI_PHYS_TABLE;
PART 'K4B1G16'
{===============================================================================================================================================================}
:PACK_TYPE | MATERIAL | PART_NUMBER     = EnvComp | PART_NUMBER  | JEDEC_TYPE     | DESCRIPTION                  | CLASS | COMPONENT_TYPE | HEIGHT     | LPID  | SPEED_URL | Status |RPL| AML | Bus_Unit | Days ;
{===============================================================================================================================================================}
'BGA1'     | 'IC'     | 'G38649-001'(!) = 'YES;YES;YES;UNK;ok;VLD' | 'G38649-001' | 'FBGA96_3_8MB' | '(USE SYM_2)IC,MEM,BL,DDR3,N/A,FBGA,96(C16 PAD)' | 'IC'  | 'BGA'          | '0.047 IN' | '2395' | 'http://speed.intel.com:8081/speed/module/pdm/item/pdm_item_detail_direct.asp?item_cde=G38649-001&item_rev=01&url_param=unused' | 'Conditional' | 'NO' | '2' | 'SMO_IC' | '???' 
'BGA1'     | 'EMPTY'  | 'G38649-001'(!) = 'YES;YES;YES;UNK;ok;VLD' | 'G38649-001' | 'FBGA96_3_8MB' | '(USE SYM_2)IC,MEM,BL,DDR3,N/A,FBGA,96(C16 PAD)' | 'IO'  | 'BGA'          | '0.047 IN' | '2395' | 'http://speed.intel.com:8081/speed/module/pdm/item/pdm_item_detail_direct.asp?item_cde=G38649-001&item_rev=01&url_param=unused' | 'Conditional' | 'NO' | '2' | 'SMO_IC' | '???' 
'BGA2'     | 'IC'     | 'G38649-001'(!) = 'YES;YES;YES;UNK;ok;VLD' | 'G38649-001' | 'FBGA96_3_8ME' | '(USE SYM_2)IC,MEM,BL,DDR3,N/A,FBGA,96(C14 PAD)' | 'IC'  | 'BGA'          | '0.047 IN' | '2656' | 'http://speed.intel.com:8081/speed/module/pdm/item/pdm_item_detail_direct.asp?item_cde=G38649-001&item_rev=01&url_param=unused' | 'Conditional' | 'NO' | '2' | 'SMO_IC' | '???' 
'BGA2'     | 'EMPTY'  | 'G38649-001'(!) = 'YES;YES;YES;UNK;ok;VLD' | 'G38649-001' | 'FBGA96_3_8ME' | '(USE SYM_2)IC,MEM,BL,DDR3,N/A,FBGA,96(C14 PAD)' | 'IO'  | 'BGA'          | '0.047 IN' | '2656' | 'http://speed.intel.com:8081/speed/module/pdm/item/pdm_item_detail_direct.asp?item_cde=G38649-001&item_rev=01&url_param=unused' | 'Conditional' | 'NO' | '2' | 'SMO_IC' | '???' 
END_PART
END.
